(kicad_pcb
	(version 20260206)
	(generator "pcbnew")
	(generator_version "10.0")
	(general
		(thickness 1.6)
		(legacy_teardrops no)
	)
	(paper "A4")
	(title_block
		(title "04192023_DAF0TMB3IC0_F0TG_MB_C_brd_V02_OCP.brd")
		(comment 1 "Grand Teton / footprint 4612 of 8354 (J32), pads 227-291 of 291")
	)
	(layers
		(0 "F.Cu" signal "TOP")
		(4 "In1.Cu" signal "GND")
		(6 "In2.Cu" signal "IN1")
		(8 "In3.Cu" signal "GND1")
		(10 "In4.Cu" signal "IN2")
		(12 "In5.Cu" signal "GND2")
		(14 "In6.Cu" signal "IN3")
		(16 "In7.Cu" signal "GND3")
		(18 "In8.Cu" signal "VCC")
		(20 "In9.Cu" signal "VCC1")
		(22 "In10.Cu" signal "GND4")
		(24 "In11.Cu" signal "IN4")
		(26 "In12.Cu" signal "GND5")
		(28 "In13.Cu" signal "IN5")
		(30 "In14.Cu" signal "GND6")
		(32 "In15.Cu" signal "IN6")
		(34 "In16.Cu" signal "GND7")
		(2 "B.Cu" signal "BOTTOM")
		(9 "F.Adhes" user "F.Adhesive")
		(11 "B.Adhes" user "B.Adhesive")
		(13 "F.Paste" user "Package Geometry/Pastemask Top")
		(15 "B.Paste" user "Package Geometry/Pastemask Bottom")
		(5 "F.SilkS" user "Ref Des/Silkscreen Top")
		(7 "B.SilkS" user "Ref Des/Silkscreen Bottom")
		(1 "F.Mask" user "Board Geometry/Soldermask Top")
		(3 "B.Mask" user "Board Geometry/Soldermask Bottom")
		(17 "Dwgs.User" user "User.Drawings")
		(19 "Cmts.User" user "User.Comments")
		(21 "Eco1.User" user "User.Eco1")
		(23 "Eco2.User" user "User.Eco2")
		(25 "Edge.Cuts" user "Board Geometry/Outline")
		(27 "Margin" user)
		(31 "F.CrtYd" user "Package Geometry/Place Bound Top")
		(29 "B.CrtYd" user "Package Geometry/Place Bound Bottom")
		(35 "F.Fab" user "Ref Des/Assembly Top")
		(33 "B.Fab" user "Ref Des/Assembly Bottom")
	)
	(footprint ""
		(layer "F.Cu")
		(at 27.20213 -255.560322 180)
		(property "Reference" "J32"
			(at 1.80086 -81.974436 0)
			(unlocked yes)
			(layer "F.SilkS")
			(effects
				(font
					(size 0.7874 0.5842)
					(thickness 0.1524)
				)
			)
		)
		(property "Value" ""
			(at 0 0 180)
			(layer "F.Fab")
			(effects
				(font
					(size 1.27 1.27)
				)
			)
		)
		(duplicate_pad_numbers_are_jumpers no)
		(pad "227" smd rect
			(at 2.050034 11.474958 90)
			(size 0.519938 1.4986)
			(layers "F.Cu" "F.Mask" "F.Paste")
			(net "M_E_CPU1_SB_PAR")
		)
		(pad "228" smd rect
			(at 2.050034 12.325096 90)
			(size 0.519938 1.4986)
			(layers "F.Cu" "F.Mask" "F.Paste")
			(net "GND")
		)
		(pad "229" smd rect
			(at 2.050034 13.17498 90)
			(size 0.519938 1.4986)
			(layers "F.Cu" "F.Mask" "F.Paste")
			(net "M_E_CPU1_SB_CS_N<1>")
		)
		(pad "230" smd rect
			(at 2.050034 14.025118 90)
			(size 0.519938 1.4986)
			(layers "F.Cu" "F.Mask" "F.Paste")
			(net "GND")
		)
		(pad "231" smd rect
			(at 2.050034 14.875002 90)
			(size 0.519938 1.4986)
			(layers "F.Cu" "F.Mask" "F.Paste")
			(net "Net_2317")
		)
		(pad "232" smd rect
			(at 2.050034 15.724886 90)
			(size 0.519938 1.4986)
			(layers "F.Cu" "F.Mask" "F.Paste")
			(net "Net_2318")
		)
		(pad "233" smd rect
			(at 2.050034 16.575024 90)
			(size 0.519938 1.4986)
			(layers "F.Cu" "F.Mask" "F.Paste")
			(net "GND")
		)
		(pad "234" smd rect
			(at 2.050034 17.424908 90)
			(size 0.519938 1.4986)
			(layers "F.Cu" "F.Mask" "F.Paste")
			(net "M_E_CPU1_SB_CB<6>")
		)
		(pad "235" smd rect
			(at 2.050034 18.275046 90)
			(size 0.519938 1.4986)
			(layers "F.Cu" "F.Mask" "F.Paste")
			(net "GND")
		)
		(pad "236" smd rect
			(at 2.050034 19.12493 90)
			(size 0.519938 1.4986)
			(layers "F.Cu" "F.Mask" "F.Paste")
			(net "M_E_CPU1_SB_CB<7>")
		)
		(pad "237" smd rect
			(at 2.050034 19.975068 90)
			(size 0.519938 1.4986)
			(layers "F.Cu" "F.Mask" "F.Paste")
			(net "GND")
		)
		(pad "238" smd rect
			(at 2.050034 20.824952 90)
			(size 0.519938 1.4986)
			(layers "F.Cu" "F.Mask" "F.Paste")
			(net "M_E_CPU1_SB_DQS_DN<4>")
		)
		(pad "239" smd rect
			(at 2.050034 21.67509 90)
			(size 0.519938 1.4986)
			(layers "F.Cu" "F.Mask" "F.Paste")
			(net "M_E_CPU1_SB_DQS_DP<4>")
		)
		(pad "240" smd rect
			(at 2.050034 22.524974 90)
			(size 0.519938 1.4986)
			(layers "F.Cu" "F.Mask" "F.Paste")
			(net "GND")
		)
		(pad "241" smd rect
			(at 2.050034 23.375112 90)
			(size 0.519938 1.4986)
			(layers "F.Cu" "F.Mask" "F.Paste")
			(net "M_E_CPU1_SB_CB<2>")
		)
		(pad "242" smd rect
			(at 2.050034 24.224996 90)
			(size 0.519938 1.4986)
			(layers "F.Cu" "F.Mask" "F.Paste")
			(net "GND")
		)
		(pad "243" smd rect
			(at 2.050034 25.07488 90)
			(size 0.519938 1.4986)
			(layers "F.Cu" "F.Mask" "F.Paste")
			(net "M_E_CPU1_SB_CB<3>")
		)
		(pad "244" smd rect
			(at 2.050034 25.925018 90)
			(size 0.519938 1.4986)
			(layers "F.Cu" "F.Mask" "F.Paste")
			(net "GND")
		)
		(pad "245" smd rect
			(at 2.050034 26.774902 90)
			(size 0.519938 1.4986)
			(layers "F.Cu" "F.Mask" "F.Paste")
			(net "M_E_CPU1_SB_DQ<2>")
		)
		(pad "246" smd rect
			(at 2.050034 27.62504 90)
			(size 0.519938 1.4986)
			(layers "F.Cu" "F.Mask" "F.Paste")
			(net "GND")
		)
		(pad "247" smd rect
			(at 2.050034 28.474924 90)
			(size 0.519938 1.4986)
			(layers "F.Cu" "F.Mask" "F.Paste")
			(net "M_E_CPU1_SB_DQ<3>")
		)
		(pad "248" smd rect
			(at 2.050034 29.325062 90)
			(size 0.519938 1.4986)
			(layers "F.Cu" "F.Mask" "F.Paste")
			(net "GND")
		)
		(pad "249" smd rect
			(at 2.050034 30.174946 90)
			(size 0.519938 1.4986)
			(layers "F.Cu" "F.Mask" "F.Paste")
			(net "M_E_CPU1_SB_DQS_DN<5>")
		)
		(pad "250" smd rect
			(at 2.050034 31.025084 90)
			(size 0.519938 1.4986)
			(layers "F.Cu" "F.Mask" "F.Paste")
			(net "M_E_CPU1_SB_DQS_DP<5>")
		)
		(pad "251" smd rect
			(at 2.050034 31.874968 90)
			(size 0.519938 1.4986)
			(layers "F.Cu" "F.Mask" "F.Paste")
			(net "GND")
		)
		(pad "252" smd rect
			(at 2.050034 32.725106 90)
			(size 0.519938 1.4986)
			(layers "F.Cu" "F.Mask" "F.Paste")
			(net "M_E_CPU1_SB_DQ<6>")
		)
		(pad "253" smd rect
			(at 2.050034 33.57499 90)
			(size 0.519938 1.4986)
			(layers "F.Cu" "F.Mask" "F.Paste")
			(net "GND")
		)
		(pad "254" smd rect
			(at 2.050034 34.425128 90)
			(size 0.519938 1.4986)
			(layers "F.Cu" "F.Mask" "F.Paste")
			(net "M_E_CPU1_SB_DQ<7>")
		)
		(pad "255" smd rect
			(at 2.050034 35.275012 90)
			(size 0.519938 1.4986)
			(layers "F.Cu" "F.Mask" "F.Paste")
			(net "GND")
		)
		(pad "256" smd rect
			(at 2.050034 36.124896 90)
			(size 0.519938 1.4986)
			(layers "F.Cu" "F.Mask" "F.Paste")
			(net "M_E_CPU1_SB_DQ<10>")
		)
		(pad "257" smd rect
			(at 2.050034 36.975034 90)
			(size 0.519938 1.4986)
			(layers "F.Cu" "F.Mask" "F.Paste")
			(net "GND")
		)
		(pad "258" smd rect
			(at 2.050034 37.824918 90)
			(size 0.519938 1.4986)
			(layers "F.Cu" "F.Mask" "F.Paste")
			(net "M_E_CPU1_SB_DQ<11>")
		)
		(pad "259" smd rect
			(at 2.050034 38.675056 90)
			(size 0.519938 1.4986)
			(layers "F.Cu" "F.Mask" "F.Paste")
			(net "GND")
		)
		(pad "260" smd rect
			(at 2.050034 39.52494 90)
			(size 0.519938 1.4986)
			(layers "F.Cu" "F.Mask" "F.Paste")
			(net "M_E_CPU1_SB_DQS_DN<6>")
		)
		(pad "261" smd rect
			(at 2.050034 40.375078 90)
			(size 0.519938 1.4986)
			(layers "F.Cu" "F.Mask" "F.Paste")
			(net "M_E_CPU1_SB_DQS_DP<6>")
		)
		(pad "262" smd rect
			(at 2.050034 41.224962 90)
			(size 0.519938 1.4986)
			(layers "F.Cu" "F.Mask" "F.Paste")
			(net "GND")
		)
		(pad "263" smd rect
			(at 2.050034 42.0751 90)
			(size 0.519938 1.4986)
			(layers "F.Cu" "F.Mask" "F.Paste")
			(net "M_E_CPU1_SB_DQ<14>")
		)
		(pad "264" smd rect
			(at 2.050034 42.924984 90)
			(size 0.519938 1.4986)
			(layers "F.Cu" "F.Mask" "F.Paste")
			(net "GND")
		)
		(pad "265" smd rect
			(at 2.050034 43.775122 90)
			(size 0.519938 1.4986)
			(layers "F.Cu" "F.Mask" "F.Paste")
			(net "M_E_CPU1_SB_DQ<15>")
		)
		(pad "266" smd rect
			(at 2.050034 44.625006 90)
			(size 0.519938 1.4986)
			(layers "F.Cu" "F.Mask" "F.Paste")
			(net "GND")
		)
		(pad "267" smd rect
			(at 2.050034 45.47489 90)
			(size 0.519938 1.4986)
			(layers "F.Cu" "F.Mask" "F.Paste")
			(net "M_E_CPU1_SB_DQ<18>")
		)
		(pad "268" smd rect
			(at 2.050034 46.325028 90)
			(size 0.519938 1.4986)
			(layers "F.Cu" "F.Mask" "F.Paste")
			(net "GND")
		)
		(pad "269" smd rect
			(at 2.050034 47.174912 90)
			(size 0.519938 1.4986)
			(layers "F.Cu" "F.Mask" "F.Paste")
			(net "M_E_CPU1_SB_DQ<19>")
		)
		(pad "270" smd rect
			(at 2.050034 48.02505 90)
			(size 0.519938 1.4986)
			(layers "F.Cu" "F.Mask" "F.Paste")
			(net "GND")
		)
		(pad "271" smd rect
			(at 2.050034 48.874934 90)
			(size 0.519938 1.4986)
			(layers "F.Cu" "F.Mask" "F.Paste")
			(net "M_E_CPU1_SB_DQS_DN<7>")
		)
		(pad "272" smd rect
			(at 2.050034 49.725072 90)
			(size 0.519938 1.4986)
			(layers "F.Cu" "F.Mask" "F.Paste")
			(net "M_E_CPU1_SB_DQS_DP<7>")
		)
		(pad "273" smd rect
			(at 2.050034 50.574956 90)
			(size 0.519938 1.4986)
			(layers "F.Cu" "F.Mask" "F.Paste")
			(net "GND")
		)
		(pad "274" smd rect
			(at 2.050034 51.425094 90)
			(size 0.519938 1.4986)
			(layers "F.Cu" "F.Mask" "F.Paste")
			(net "M_E_CPU1_SB_DQ<22>")
		)
		(pad "275" smd rect
			(at 2.050034 52.274978 90)
			(size 0.519938 1.4986)
			(layers "F.Cu" "F.Mask" "F.Paste")
			(net "GND")
		)
		(pad "276" smd rect
			(at 2.050034 53.125116 90)
			(size 0.519938 1.4986)
			(layers "F.Cu" "F.Mask" "F.Paste")
			(net "M_E_CPU1_SB_DQ<23>")
		)
		(pad "277" smd rect
			(at 2.050034 53.975 90)
			(size 0.519938 1.4986)
			(layers "F.Cu" "F.Mask" "F.Paste")
			(net "GND")
		)
		(pad "278" smd rect
			(at 2.050034 54.824884 90)
			(size 0.519938 1.4986)
			(layers "F.Cu" "F.Mask" "F.Paste")
			(net "M_E_CPU1_SB_DQ<26>")
		)
		(pad "279" smd rect
			(at 2.050034 55.675022 90)
			(size 0.519938 1.4986)
			(layers "F.Cu" "F.Mask" "F.Paste")
			(net "GND")
		)
		(pad "280" smd rect
			(at 2.050034 56.524906 90)
			(size 0.519938 1.4986)
			(layers "F.Cu" "F.Mask" "F.Paste")
			(net "M_E_CPU1_SB_DQ<27>")
		)
		(pad "281" smd rect
			(at 2.050034 57.375044 90)
			(size 0.519938 1.4986)
			(layers "F.Cu" "F.Mask" "F.Paste")
			(net "GND")
		)
		(pad "282" smd rect
			(at 2.050034 58.224928 90)
			(size 0.519938 1.4986)
			(layers "F.Cu" "F.Mask" "F.Paste")
			(net "M_E_CPU1_SB_DQS_DN<8>")
		)
		(pad "283" smd rect
			(at 2.050034 59.075066 90)
			(size 0.519938 1.4986)
			(layers "F.Cu" "F.Mask" "F.Paste")
			(net "M_E_CPU1_SB_DQS_DP<8>")
		)
		(pad "284" smd rect
			(at 2.050034 59.92495 90)
			(size 0.519938 1.4986)
			(layers "F.Cu" "F.Mask" "F.Paste")
			(net "GND")
		)
		(pad "285" smd rect
			(at 2.050034 60.775088 90)
			(size 0.519938 1.4986)
			(layers "F.Cu" "F.Mask" "F.Paste")
			(net "M_E_CPU1_SB_DQ<30>")
		)
		(pad "286" smd rect
			(at 2.050034 61.624972 90)
			(size 0.519938 1.4986)
			(layers "F.Cu" "F.Mask" "F.Paste")
			(net "GND")
		)
		(pad "287" smd rect
			(at 2.050034 62.47511 90)
			(size 0.519938 1.4986)
			(layers "F.Cu" "F.Mask" "F.Paste")
			(net "M_E_CPU1_SB_DQ<31>")
		)
		(pad "288" smd rect
			(at 2.050034 63.324994 90)
			(size 0.519938 1.4986)
			(layers "F.Cu" "F.Mask" "F.Paste")
			(net "GND")
		)
		(pad "G1" thru_hole oval
			(at 0 -68.97497 90)
			(size 1.7272 3.4798)
			(drill oval 1.2192 2.4638)
			(layers "*.Cu" "*.Mask")
			(remove_unused_layers no)
			(net "GND")
			(clearance 0.127)
			(thermal_gap 0.127)
		)
		(pad "G2" thru_hole oval
			(at 0 3.875024 90)
			(size 1.7272 3.4798)
			(drill oval 1.2192 2.4638)
			(layers "*.Cu" "*.Mask")
			(remove_unused_layers no)
			(net "GND")
			(clearance 0.127)
			(thermal_gap 0.127)
		)
		(pad "G3" thru_hole oval
			(at 0 68.97497 90)
			(size 1.7272 3.4798)
			(drill oval 1.2192 2.4638)
			(layers "*.Cu" "*.Mask")
			(remove_unused_layers no)
			(net "GND")
			(clearance 0.127)
			(thermal_gap 0.127)
		)
	)
)
